FILE_TYPE = CONNECTIVITY;
{Allegro Design Entry HDL 17.2-2016 S081 (4005846) 1/11/2022}
"PAGE_NUMBER" = 247;
0"NC";
END.
